# S9S_MB_2U (Grand Teton) — schematic netlist excerpt (pin names and nets, part order shuffled) for the footprints in the layout excerpt that follows; sources: Cadence DE-HDL packaged netlist, KiCad conversion of 03242023_DA0F0TMBIJ0_F0T_Motherboard_J_brd_V01_OCP.brd

R186  Q_RES  100 1% CHIP  pkg 0402LF  page 124 : A = RST_CPU0_BUF_R_N ; B = RST_CPU0_LVC1_N
R4535  Q_RES  10 1% CHIP  pkg 0402LF  page 240 : A = CLK_100M_BMC_P3E_DP ; B = CLK_100M_BMC_P3E_DP_R

(kicad_pcb
	(version 20260206)
	(generator "pcbnew")
	(generator_version "10.0")
	(general
		(thickness 1.6)
		(legacy_teardrops no)
	)
	(paper "A4")
	(title_block
		(title "03242023_DA0F0TMBIJ0_F0T_Motherboard_J_brd_V01_OCP.brd")
		(comment 1 "Grand Teton / footprints 6062-6063 of 6105")
	)
	(layers
		(0 "F.Cu" signal "TOP")
		(4 "In1.Cu" signal "GND")
		(6 "In2.Cu" signal "IN1")
		(8 "In3.Cu" signal "GND1")
		(10 "In4.Cu" signal "IN2")
		(12 "In5.Cu" signal "GND2")
		(14 "In6.Cu" signal "IN3")
		(16 "In7.Cu" signal "GND3")
		(18 "In8.Cu" signal "VCC")
		(20 "In9.Cu" signal "VCC1")
		(22 "In10.Cu" signal "GND4")
		(24 "In11.Cu" signal "IN4")
		(26 "In12.Cu" signal "GND5")
		(28 "In13.Cu" signal "IN5")
		(30 "In14.Cu" signal "GND6")
		(32 "In15.Cu" signal "IN6")
		(34 "In16.Cu" signal "GND7")
		(2 "B.Cu" signal "BOTTOM")
		(9 "F.Adhes" user "F.Adhesive")
		(11 "B.Adhes" user "B.Adhesive")
		(13 "F.Paste" user "Package Geometry/Pastemask Top")
		(15 "B.Paste" user "Package Geometry/Pastemask Bottom")
		(5 "F.SilkS" user "Ref Des/Silkscreen Top")
		(7 "B.SilkS" user "Ref Des/Silkscreen Bottom")
		(1 "F.Mask" user "Board Geometry/Soldermask Top")
		(3 "B.Mask" user "Board Geometry/Soldermask Bottom")
		(17 "Dwgs.User" user "User.Drawings")
		(19 "Cmts.User" user "User.Comments")
		(21 "Eco1.User" user "User.Eco1")
		(23 "Eco2.User" user "User.Eco2")
		(25 "Edge.Cuts" user "Board Geometry/Outline")
		(27 "Margin" user)
		(31 "F.CrtYd" user "Package Geometry/Place Bound Top")
		(29 "B.CrtYd" user "Package Geometry/Place Bound Bottom")
		(35 "F.Fab" user "Ref Des/Assembly Top")
		(33 "B.Fab" user "Ref Des/Assembly Bottom")
	)
	(footprint ""
		(layer "B.Cu")
		(at 297.942 -259.171948 180)
		(property "Reference" "R186"
			(at 0 0 0)
			(layer "B.SilkS")
			(hide yes)
			(effects
				(font
					(size 1.27 1.27)
				)
				(justify mirror)
			)
		)
		(property "Value" ""
			(at 0 0 0)
			(layer "B.Fab")
			(effects
				(font
					(size 1.27 1.27)
				)
				(justify mirror)
			)
		)
		(duplicate_pad_numbers_are_jumpers no)
		(fp_line
			(start 0.7874 0.4064)
			(end 0.7874 -0.4064)
			(stroke
				(width 0.1524)
				(type default)
			)
			(layer "B.SilkS")
		)
		(fp_line
			(start 0.7874 -0.4064)
			(end -0.7874 -0.4064)
			(stroke
				(width 0.1524)
				(type default)
			)
			(layer "B.SilkS")
		)
		(fp_line
			(start -0.7874 0.4064)
			(end 0.7874 0.4064)
			(stroke
				(width 0.1524)
				(type default)
			)
			(layer "B.SilkS")
		)
		(fp_line
			(start -0.7874 -0.4064)
			(end -0.7874 0.4064)
			(stroke
				(width 0.1524)
				(type default)
			)
			(layer "B.SilkS")
		)
		(fp_line
			(start 0.67945 0.3048)
			(end 0.67945 -0.305054)
			(stroke
				(width 0.1)
				(type default)
			)
			(layer "B.Fab")
		)
		(fp_line
			(start 0.67945 -0.305054)
			(end 0.12065 -0.305054)
			(stroke
				(width 0.1)
				(type default)
			)
			(layer "B.Fab")
		)
		(fp_line
			(start 0.12065 0.3048)
			(end 0.67945 0.3048)
			(stroke
				(width 0.1)
				(type default)
			)
			(layer "B.Fab")
		)
		(fp_line
			(start 0.12065 0.2794)
			(end 0.12065 0.3048)
			(stroke
				(width 0.1)
				(type default)
			)
			(layer "B.Fab")
		)
		(fp_line
			(start 0.12065 -0.2794)
			(end -0.12065 -0.2794)
			(stroke
				(width 0.1)
				(type default)
			)
			(layer "B.Fab")
		)
		(fp_line
			(start 0.12065 -0.305054)
			(end 0.12065 -0.2794)
			(stroke
				(width 0.1)
				(type default)
			)
			(layer "B.Fab")
		)
		(fp_line
			(start -0.120396 0.3048)
			(end -0.120396 0.2794)
			(stroke
				(width 0.1)
				(type default)
			)
			(layer "B.Fab")
		)
		(fp_line
			(start -0.120396 0.2794)
			(end 0.12065 0.2794)
			(stroke
				(width 0.1)
				(type default)
			)
			(layer "B.Fab")
		)
		(fp_line
			(start -0.12065 -0.2794)
			(end -0.12065 -0.3048)
			(stroke
				(width 0.1)
				(type default)
			)
			(layer "B.Fab")
		)
		(fp_line
			(start -0.12065 -0.3048)
			(end -0.67945 -0.3048)
			(stroke
				(width 0.1)
				(type default)
			)
			(layer "B.Fab")
		)
		(fp_line
			(start -0.67945 0.3048)
			(end -0.120396 0.3048)
			(stroke
				(width 0.1)
				(type default)
			)
			(layer "B.Fab")
		)
		(fp_line
			(start -0.67945 -0.3048)
			(end -0.67945 0.3048)
			(stroke
				(width 0.1)
				(type default)
			)
			(layer "B.Fab")
		)
		(pad "1" smd circle
			(at 0.40005 0)
			(size 0 0)
			(layers "B.Cu" "B.Mask" "B.Paste")
			(net "RST_CPU0_BUF_R_N")
		)
		(pad "2" smd circle
			(at -0.40005 0)
			(size 0 0)
			(layers "B.Cu" "B.Mask" "B.Paste")
			(net "RST_CPU0_LVC1_N")
		)
	)
	(footprint ""
		(layer "B.Cu")
		(at 171.21632 -13.762228 90)
		(property "Reference" "R4535"
			(at 0 0 90)
			(layer "B.SilkS")
			(hide yes)
			(effects
				(font
					(size 1.27 1.27)
				)
				(justify mirror)
			)
		)
		(property "Value" ""
			(at 0 0 90)
			(layer "B.Fab")
			(effects
				(font
					(size 1.27 1.27)
				)
				(justify mirror)
			)
		)
		(duplicate_pad_numbers_are_jumpers no)
		(fp_line
			(start 0.4064 -0.4064)
			(end -0.11176 -0.4064)
			(stroke
				(width 0.1524)
				(type default)
			)
			(layer "B.SilkS")
		)
		(fp_line
			(start -0.7874 -0.16002)
			(end -0.7874 0.4064)
			(stroke
				(width 0.1524)
				(type default)
			)
			(layer "B.SilkS")
		)
		(fp_line
			(start 0.7874 0.4064)
			(end 0.7874 -0.0508)
			(stroke
				(width 0.1524)
				(type default)
			)
			(layer "B.SilkS")
		)
		(fp_line
			(start -0.7874 0.4064)
			(end 0.7874 0.4064)
			(stroke
				(width 0.1524)
				(type default)
			)
			(layer "B.SilkS")
		)
		(fp_line
			(start 0.67945 -0.305054)
			(end 0.12065 -0.305054)
			(stroke
				(width 0.1)
				(type default)
			)
			(layer "B.Fab")
		)
		(fp_line
			(start 0.12065 -0.305054)
			(end 0.12065 -0.2794)
			(stroke
				(width 0.1)
				(type default)
			)
			(layer "B.Fab")
		)
		(fp_line
			(start -0.12065 -0.3048)
			(end -0.67945 -0.3048)
			(stroke
				(width 0.1)
				(type default)
			)
			(layer "B.Fab")
		)
		(fp_line
			(start -0.67945 -0.3048)
			(end -0.67945 0.3048)
			(stroke
				(width 0.1)
				(type default)
			)
			(layer "B.Fab")
		)
		(fp_line
			(start 0.12065 -0.2794)
			(end -0.12065 -0.2794)
			(stroke
				(width 0.1)
				(type default)
			)
			(layer "B.Fab")
		)
		(fp_line
			(start -0.12065 -0.2794)
			(end -0.12065 -0.3048)
			(stroke
				(width 0.1)
				(type default)
			)
			(layer "B.Fab")
		)
		(fp_line
			(start 0.12065 0.2794)
			(end 0.12065 0.3048)
			(stroke
				(width 0.1)
				(type default)
			)
			(layer "B.Fab")
		)
		(fp_line
			(start -0.120396 0.2794)
			(end 0.12065 0.2794)
			(stroke
				(width 0.1)
				(type default)
			)
			(layer "B.Fab")
		)
		(fp_line
			(start 0.67945 0.3048)
			(end 0.67945 -0.305054)
			(stroke
				(width 0.1)
				(type default)
			)
			(layer "B.Fab")
		)
		(fp_line
			(start 0.12065 0.3048)
			(end 0.67945 0.3048)
			(stroke
				(width 0.1)
				(type default)
			)
			(layer "B.Fab")
		)
		(fp_line
			(start -0.120396 0.3048)
			(end -0.120396 0.2794)
			(stroke
				(width 0.1)
				(type default)
			)
			(layer "B.Fab")
		)
		(fp_line
			(start -0.67945 0.3048)
			(end -0.120396 0.3048)
			(stroke
				(width 0.1)
				(type default)
			)
			(layer "B.Fab")
		)
		(pad "1" smd circle
			(at 0.40005 0 270)
			(size 0 0)
			(layers "B.Cu" "B.Mask" "B.Paste")
			(net "CLK_100M_BMC_P3E_DP")
		)
		(pad "2" smd circle
			(at -0.40005 0 270)
			(size 0 0)
			(layers "B.Cu" "B.Mask" "B.Paste")
			(net "CLK_100M_BMC_P3E_DP_R")
		)
	)
)
